(kicad_pcb
	(version 20260206)
	(generator "pcbnew")
	(generator_version "10.0")
	(general
		(thickness 1.6)
		(legacy_teardrops no)
	)
	(paper "A4")
	(title_block
		(title "01162023_DA0F0TEBIF0_F0T_Expander_BD_F_brd_V02_OCP.brd")
		(comment 1 "Grand Teton / footprints 1479-1487 of 9728")
	)
	(layers
		(0 "F.Cu" signal "TOP")
		(4 "In1.Cu" signal "GND")
		(6 "In2.Cu" signal "VCC")
		(8 "In3.Cu" signal "VCC1")
		(10 "In4.Cu" signal "GND1")
		(12 "In5.Cu" signal "IN1")
		(14 "In6.Cu" signal "GND2")
		(16 "In7.Cu" signal "IN2")
		(18 "In8.Cu" signal "GND3")
		(20 "In9.Cu" signal "IN3")
		(22 "In10.Cu" signal "GND4")
		(24 "In11.Cu" signal "IN4")
		(26 "In12.Cu" signal "GND5")
		(28 "In13.Cu" signal "IN5")
		(30 "In14.Cu" signal "GND6")
		(32 "In15.Cu" signal "IN6")
		(34 "In16.Cu" signal "GND7")
		(2 "B.Cu" signal "BOTTOM")
		(9 "F.Adhes" user "F.Adhesive")
		(11 "B.Adhes" user "B.Adhesive")
		(13 "F.Paste" user "Package Geometry/Pastemask Top")
		(15 "B.Paste" user "Package Geometry/Pastemask Bottom")
		(5 "F.SilkS" user "Ref Des/Silkscreen Top")
		(7 "B.SilkS" user "Ref Des/Silkscreen Bottom")
		(1 "F.Mask" user "Board Geometry/Soldermask Top")
		(3 "B.Mask" user "Board Geometry/Soldermask Bottom")
		(17 "Dwgs.User" user "User.Drawings")
		(19 "Cmts.User" user "User.Comments")
		(21 "Eco1.User" user "User.Eco1")
		(23 "Eco2.User" user "User.Eco2")
		(25 "Edge.Cuts" user "Board Geometry/Outline")
		(27 "Margin" user)
		(31 "F.CrtYd" user "Package Geometry/Place Bound Top")
		(29 "B.CrtYd" user "Package Geometry/Place Bound Bottom")
		(35 "F.Fab" user "Ref Des/Assembly Top")
		(33 "B.Fab" user "Ref Des/Assembly Bottom")
	)
	(footprint ""
		(layer "F.Cu")
		(at 334.229456 -277.639272 180)
		(property "Reference" "PC158"
			(at 0 0 180)
			(layer "F.SilkS")
			(hide yes)
			(effects
				(font
					(size 1.27 1.27)
				)
			)
		)
		(property "Value" ""
			(at 0 0 180)
			(layer "F.Fab")
			(effects
				(font
					(size 1.27 1.27)
				)
			)
		)
		(duplicate_pad_numbers_are_jumpers no)
		(fp_line
			(start 1.524 0.762)
			(end -1.524 0.762)
			(stroke
				(width 0.1524)
				(type default)
			)
			(layer "F.SilkS")
		)
		(fp_line
			(start 1.524 -0.762)
			(end 1.524 0.762)
			(stroke
				(width 0.1524)
				(type default)
			)
			(layer "F.SilkS")
		)
		(fp_line
			(start -1.524 0.762)
			(end -1.524 -0.762)
			(stroke
				(width 0.1524)
				(type default)
			)
			(layer "F.SilkS")
		)
		(fp_line
			(start -1.524 -0.762)
			(end 1.524 -0.762)
			(stroke
				(width 0.1524)
				(type default)
			)
			(layer "F.SilkS")
		)
		(fp_line
			(start 1.1049 0.724916)
			(end 1.1049 -0.724916)
			(stroke
				(width 0.1)
				(type default)
			)
			(layer "F.Fab")
		)
		(fp_line
			(start 1.1049 -0.724916)
			(end -1.1049 -0.724916)
			(stroke
				(width 0.1)
				(type default)
			)
			(layer "F.Fab")
		)
		(fp_line
			(start -1.1049 0.724916)
			(end 1.1049 0.724916)
			(stroke
				(width 0.1)
				(type default)
			)
			(layer "F.Fab")
		)
		(fp_line
			(start -1.1049 -0.724916)
			(end -1.1049 0.724916)
			(stroke
				(width 0.1)
				(type default)
			)
			(layer "F.Fab")
		)
		(pad "1" smd rect
			(at -0.889 0)
			(size 1.016 1.27)
			(layers "F.Cu" "F.Mask" "F.Paste")
			(net "SW_P12V_P0V8_PEX2_FLT")
		)
		(pad "2" smd rect
			(at 0.889 0)
			(size 1.016 1.27)
			(layers "F.Cu" "F.Mask" "F.Paste")
			(net "GND")
		)
	)
	(footprint ""
		(layer "F.Cu")
		(at 486.08234 -546.564566 180)
		(property "Reference" "SCREW_SSD9_2"
			(at -5.207 -1.402334 0)
			(unlocked yes)
			(layer "B.SilkS")
			(effects
				(font
					(size 0.7874 0.5842)
					(thickness 0.1524)
				)
				(justify mirror)
			)
		)
		(property "Value" ""
			(at 0 0 180)
			(layer "F.Fab")
			(effects
				(font
					(size 1.27 1.27)
				)
			)
		)
		(duplicate_pad_numbers_are_jumpers no)
		(pad "1" thru_hole circle
			(at 0 0 180)
			(size 0.4572 0.4572)
			(drill 0.2032)
			(layers "*.Cu" "*.Mask")
			(remove_unused_layers no)
			(net "Net_9125")
			(clearance 0.127)
			(thermal_gap 0.127)
			(padstack
				(mode front_inner_back)
				(layer "Inner"
					(shape circle)
					(size 0.4572 0.4572)
					(clearance 0.127)
				)
				(layer "B.Cu"
					(shape circle)
					(size 0.508 0.508)
					(clearance 0.1016)
				)
			)
		)
	)
	(footprint ""
		(layer "F.Cu")
		(at 86.218522 -343.952322 90)
		(property "Reference" "C151"
			(at 0 0 90)
			(layer "F.SilkS")
			(hide yes)
			(effects
				(font
					(size 1.27 1.27)
				)
			)
		)
		(property "Value" ""
			(at 0 0 90)
			(layer "F.Fab")
			(effects
				(font
					(size 1.27 1.27)
				)
			)
		)
		(duplicate_pad_numbers_are_jumpers no)
		(fp_line
			(start 0.299974 -0.150114)
			(end 0.299974 0.150114)
			(stroke
				(width 0.1)
				(type default)
			)
			(layer "F.Fab")
		)
		(fp_line
			(start -0.299974 -0.150114)
			(end 0.299974 -0.150114)
			(stroke
				(width 0.1)
				(type default)
			)
			(layer "F.Fab")
		)
		(fp_line
			(start 0.299974 0.150114)
			(end -0.299974 0.150114)
			(stroke
				(width 0.1)
				(type default)
			)
			(layer "F.Fab")
		)
		(fp_line
			(start -0.299974 0.150114)
			(end -0.299974 -0.150114)
			(stroke
				(width 0.1)
				(type default)
			)
			(layer "F.Fab")
		)
		(pad "1" smd rect
			(at -0.2667 0 90)
			(size 0.3048 0.381)
			(layers "F.Cu" "F.Mask" "F.Paste")
			(net "P5E_PEX0_STN6_TX_DP<100>")
		)
		(pad "2" smd rect
			(at 0.2667 0 90)
			(size 0.3048 0.381)
			(layers "F.Cu" "F.Mask" "F.Paste")
			(net "P5E_PEX0_STN6_TX_C_DP<100>")
		)
	)
	(footprint ""
		(layer "F.Cu")
		(at 129.690114 -258.131564 180)
		(property "Reference" "R831"
			(at 0 0 180)
			(layer "F.SilkS")
			(hide yes)
			(effects
				(font
					(size 1.27 1.27)
				)
			)
		)
		(property "Value" ""
			(at 0 0 180)
			(layer "F.Fab")
			(effects
				(font
					(size 1.27 1.27)
				)
			)
		)
		(duplicate_pad_numbers_are_jumpers no)
		(fp_line
			(start 0.7874 0.4064)
			(end -0.7874 0.4064)
			(stroke
				(width 0.1524)
				(type default)
			)
			(layer "F.SilkS")
		)
		(fp_line
			(start 0.7874 -0.4064)
			(end 0.7874 0.4064)
			(stroke
				(width 0.1524)
				(type default)
			)
			(layer "F.SilkS")
		)
		(fp_line
			(start -0.7874 0.4064)
			(end -0.7874 -0.4064)
			(stroke
				(width 0.1524)
				(type default)
			)
			(layer "F.SilkS")
		)
		(fp_line
			(start -0.7874 -0.4064)
			(end 0.7874 -0.4064)
			(stroke
				(width 0.1524)
				(type default)
			)
			(layer "F.SilkS")
		)
		(fp_line
			(start 0.67945 0.3048)
			(end 0.120396 0.3048)
			(stroke
				(width 0.1)
				(type default)
			)
			(layer "F.Fab")
		)
		(fp_line
			(start 0.67945 -0.3048)
			(end 0.67945 0.3048)
			(stroke
				(width 0.1)
				(type default)
			)
			(layer "F.Fab")
		)
		(fp_line
			(start 0.12065 -0.2794)
			(end 0.12065 -0.3048)
			(stroke
				(width 0.1)
				(type default)
			)
			(layer "F.Fab")
		)
		(fp_line
			(start 0.12065 -0.3048)
			(end 0.67945 -0.3048)
			(stroke
				(width 0.1)
				(type default)
			)
			(layer "F.Fab")
		)
		(fp_line
			(start 0.120396 0.3048)
			(end 0.120396 0.2794)
			(stroke
				(width 0.1)
				(type default)
			)
			(layer "F.Fab")
		)
		(fp_line
			(start 0.120396 0.2794)
			(end -0.12065 0.2794)
			(stroke
				(width 0.1)
				(type default)
			)
			(layer "F.Fab")
		)
		(fp_line
			(start -0.12065 0.3048)
			(end -0.67945 0.3048)
			(stroke
				(width 0.1)
				(type default)
			)
			(layer "F.Fab")
		)
		(fp_line
			(start -0.12065 0.2794)
			(end -0.12065 0.3048)
			(stroke
				(width 0.1)
				(type default)
			)
			(layer "F.Fab")
		)
		(fp_line
			(start -0.12065 -0.2794)
			(end 0.12065 -0.2794)
			(stroke
				(width 0.1)
				(type default)
			)
			(layer "F.Fab")
		)
		(fp_line
			(start -0.12065 -0.305054)
			(end -0.12065 -0.2794)
			(stroke
				(width 0.1)
				(type default)
			)
			(layer "F.Fab")
		)
		(fp_line
			(start -0.67945 0.3048)
			(end -0.67945 -0.305054)
			(stroke
				(width 0.1)
				(type default)
			)
			(layer "F.Fab")
		)
		(fp_line
			(start -0.67945 -0.305054)
			(end -0.12065 -0.305054)
			(stroke
				(width 0.1)
				(type default)
			)
			(layer "F.Fab")
		)
		(pad "1" smd circle
			(at -0.40005 0 180)
			(size 0 0)
			(layers "F.Cu" "F.Mask" "F.Paste")
			(net "P3V3_AUX")
		)
		(pad "2" smd circle
			(at 0.40005 0 180)
			(size 0 0)
			(layers "F.Cu" "F.Mask" "F.Paste")
			(net "P0V8_PEX1_BVRRDY")
		)
	)
	(footprint ""
		(layer "F.Cu")
		(at 362.459016 -319.545462 90)
		(property "Reference" "L75"
			(at 0 0 90)
			(layer "F.SilkS")
			(hide yes)
			(effects
				(font
					(size 1.27 1.27)
				)
			)
		)
		(property "Value" ""
			(at 0 0 90)
			(layer "F.Fab")
			(effects
				(font
					(size 1.27 1.27)
				)
			)
		)
		(duplicate_pad_numbers_are_jumpers no)
		(fp_line
			(start 2.248154 -4.9911)
			(end -2.248154 -4.9911)
			(stroke
				(width 0.1524)
				(type default)
			)
			(layer "F.SilkS")
		)
		(fp_line
			(start -2.248154 -4.9911)
			(end -2.248154 -1.682496)
			(stroke
				(width 0.1524)
				(type default)
			)
			(layer "F.SilkS")
		)
		(fp_line
			(start 2.248154 -1.748536)
			(end 2.248154 -4.9911)
			(stroke
				(width 0.1524)
				(type default)
			)
			(layer "F.SilkS")
		)
		(fp_line
			(start -2.248154 1.787144)
			(end -2.248154 4.9911)
			(stroke
				(width 0.1524)
				(type default)
			)
			(layer "F.SilkS")
		)
		(fp_line
			(start 2.248154 4.9911)
			(end 2.248154 1.743202)
			(stroke
				(width 0.1524)
				(type default)
			)
			(layer "F.SilkS")
		)
		(fp_line
			(start -2.248154 4.9911)
			(end 2.248154 4.9911)
			(stroke
				(width 0.1524)
				(type default)
			)
			(layer "F.SilkS")
		)
		(fp_line
			(start 1.700022 -0.899922)
			(end -1.700022 -0.899922)
			(stroke
				(width 0.1)
				(type default)
			)
			(layer "F.Fab")
		)
		(fp_line
			(start -1.700022 -0.899922)
			(end -1.700022 0.899922)
			(stroke
				(width 0.1)
				(type default)
			)
			(layer "F.Fab")
		)
		(fp_line
			(start 1.700022 0.899922)
			(end 1.700022 -0.899922)
			(stroke
				(width 0.1)
				(type default)
			)
			(layer "F.Fab")
		)
		(fp_line
			(start -1.700022 0.899922)
			(end 1.700022 0.899922)
			(stroke
				(width 0.1)
				(type default)
			)
			(layer "F.Fab")
		)
		(pad "1" smd rect
			(at -1.575054 0 90)
			(size 1.1684 9.8044)
			(layers "F.Cu" "F.Mask" "F.Paste")
			(net "P0V8_PEX3")
		)
		(pad "2" smd rect
			(at 1.575054 0 90)
			(size 1.1684 9.8044)
			(layers "F.Cu" "F.Mask" "F.Paste")
			(net "P0V8_SERDES_VDDA_PEX3")
		)
	)
	(footprint ""
		(layer "F.Cu")
		(at 117.958362 -125.899926 180)
		(property "Reference" "R852"
			(at 0 0 180)
			(layer "F.SilkS")
			(hide yes)
			(effects
				(font
					(size 1.27 1.27)
				)
			)
		)
		(property "Value" ""
			(at 0 0 180)
			(layer "F.Fab")
			(effects
				(font
					(size 1.27 1.27)
				)
			)
		)
		(duplicate_pad_numbers_are_jumpers no)
		(fp_line
			(start 0.7874 0.4064)
			(end -0.7874 0.4064)
			(stroke
				(width 0.1524)
				(type default)
			)
			(layer "F.SilkS")
		)
		(fp_line
			(start 0.7874 -0.4064)
			(end 0.7874 0.4064)
			(stroke
				(width 0.1524)
				(type default)
			)
			(layer "F.SilkS")
		)
		(fp_line
			(start -0.7874 0.4064)
			(end -0.7874 -0.4064)
			(stroke
				(width 0.1524)
				(type default)
			)
			(layer "F.SilkS")
		)
		(fp_line
			(start -0.7874 -0.4064)
			(end 0.7874 -0.4064)
			(stroke
				(width 0.1524)
				(type default)
			)
			(layer "F.SilkS")
		)
		(fp_line
			(start 0.67945 0.3048)
			(end 0.120396 0.3048)
			(stroke
				(width 0.1)
				(type default)
			)
			(layer "F.Fab")
		)
		(fp_line
			(start 0.67945 -0.3048)
			(end 0.67945 0.3048)
			(stroke
				(width 0.1)
				(type default)
			)
			(layer "F.Fab")
		)
		(fp_line
			(start 0.12065 -0.2794)
			(end 0.12065 -0.3048)
			(stroke
				(width 0.1)
				(type default)
			)
			(layer "F.Fab")
		)
		(fp_line
			(start 0.12065 -0.3048)
			(end 0.67945 -0.3048)
			(stroke
				(width 0.1)
				(type default)
			)
			(layer "F.Fab")
		)
		(fp_line
			(start 0.120396 0.3048)
			(end 0.120396 0.2794)
			(stroke
				(width 0.1)
				(type default)
			)
			(layer "F.Fab")
		)
		(fp_line
			(start 0.120396 0.2794)
			(end -0.12065 0.2794)
			(stroke
				(width 0.1)
				(type default)
			)
			(layer "F.Fab")
		)
		(fp_line
			(start -0.12065 0.3048)
			(end -0.67945 0.3048)
			(stroke
				(width 0.1)
				(type default)
			)
			(layer "F.Fab")
		)
		(fp_line
			(start -0.12065 0.2794)
			(end -0.12065 0.3048)
			(stroke
				(width 0.1)
				(type default)
			)
			(layer "F.Fab")
		)
		(fp_line
			(start -0.12065 -0.2794)
			(end 0.12065 -0.2794)
			(stroke
				(width 0.1)
				(type default)
			)
			(layer "F.Fab")
		)
		(fp_line
			(start -0.12065 -0.305054)
			(end -0.12065 -0.2794)
			(stroke
				(width 0.1)
				(type default)
			)
			(layer "F.Fab")
		)
		(fp_line
			(start -0.67945 0.3048)
			(end -0.67945 -0.305054)
			(stroke
				(width 0.1)
				(type default)
			)
			(layer "F.Fab")
		)
		(fp_line
			(start -0.67945 -0.305054)
			(end -0.12065 -0.305054)
			(stroke
				(width 0.1)
				(type default)
			)
			(layer "F.Fab")
		)
		(pad "1" smd circle
			(at -0.40005 0 180)
			(size 0 0)
			(layers "F.Cu" "F.Mask" "F.Paste")
			(net "P3V3")
		)
		(pad "2" smd circle
			(at 0.40005 0 180)
			(size 0 0)
			(layers "F.Cu" "F.Mask" "F.Paste")
			(net "PWRGD_P3V3")
		)
	)
	(footprint ""
		(layer "F.Cu")
		(at 199.750172 -50.96383 180)
		(property "Reference" "PC537"
			(at 0 0 180)
			(layer "F.SilkS")
			(hide yes)
			(effects
				(font
					(size 1.27 1.27)
				)
			)
		)
		(property "Value" ""
			(at 0 0 180)
			(layer "F.Fab")
			(effects
				(font
					(size 1.27 1.27)
				)
			)
		)
		(duplicate_pad_numbers_are_jumpers no)
		(fp_line
			(start 1.524 0.762)
			(end -1.524 0.762)
			(stroke
				(width 0.1524)
				(type default)
			)
			(layer "F.SilkS")
		)
		(fp_line
			(start 1.524 -0.762)
			(end 1.524 0.762)
			(stroke
				(width 0.1524)
				(type default)
			)
			(layer "F.SilkS")
		)
		(fp_line
			(start -1.524 0.762)
			(end -1.524 -0.762)
			(stroke
				(width 0.1524)
				(type default)
			)
			(layer "F.SilkS")
		)
		(fp_line
			(start -1.524 -0.762)
			(end 1.524 -0.762)
			(stroke
				(width 0.1524)
				(type default)
			)
			(layer "F.SilkS")
		)
		(fp_line
			(start 1.1049 0.724916)
			(end 1.1049 -0.724916)
			(stroke
				(width 0.1)
				(type default)
			)
			(layer "F.Fab")
		)
		(fp_line
			(start 1.1049 -0.724916)
			(end -1.1049 -0.724916)
			(stroke
				(width 0.1)
				(type default)
			)
			(layer "F.Fab")
		)
		(fp_line
			(start -1.1049 0.724916)
			(end 1.1049 0.724916)
			(stroke
				(width 0.1)
				(type default)
			)
			(layer "F.Fab")
		)
		(fp_line
			(start -1.1049 -0.724916)
			(end -1.1049 0.724916)
			(stroke
				(width 0.1)
				(type default)
			)
			(layer "F.Fab")
		)
		(pad "1" smd rect
			(at -0.889 0)
			(size 1.016 1.27)
			(layers "F.Cu" "F.Mask" "F.Paste")
			(net "P3V3_SSD7")
		)
		(pad "2" smd rect
			(at 0.889 0)
			(size 1.016 1.27)
			(layers "F.Cu" "F.Mask" "F.Paste")
			(net "GND")
		)
	)
	(footprint ""
		(layer "F.Cu")
		(at 122.689366 -313.620404 180)
		(property "Reference" "R5789"
			(at 0 0 180)
			(layer "F.SilkS")
			(hide yes)
			(effects
				(font
					(size 1.27 1.27)
				)
			)
		)
		(property "Value" ""
			(at 0 0 180)
			(layer "F.Fab")
			(effects
				(font
					(size 1.27 1.27)
				)
			)
		)
		(duplicate_pad_numbers_are_jumpers no)
		(fp_line
			(start 2.576322 1.1303)
			(end -2.576322 1.1303)
			(stroke
				(width 0.1524)
				(type default)
			)
			(layer "F.SilkS")
		)
		(fp_line
			(start 2.576322 -1.1303)
			(end 2.576322 1.1303)
			(stroke
				(width 0.1524)
				(type default)
			)
			(layer "F.SilkS")
		)
		(fp_line
			(start -2.576322 1.1303)
			(end -2.576322 -1.1303)
			(stroke
				(width 0.1524)
				(type default)
			)
			(layer "F.SilkS")
		)
		(fp_line
			(start -2.576322 -1.1303)
			(end 2.576322 -1.1303)
			(stroke
				(width 0.1524)
				(type default)
			)
			(layer "F.SilkS")
		)
		(fp_line
			(start 1.649984 0.899922)
			(end 1.649984 -0.899922)
			(stroke
				(width 0.1)
				(type default)
			)
			(layer "F.Fab")
		)
		(fp_line
			(start 1.649984 -0.899922)
			(end -1.649984 -0.899922)
			(stroke
				(width 0.1)
				(type default)
			)
			(layer "F.Fab")
		)
		(fp_line
			(start -1.649984 0.899922)
			(end 1.649984 0.899922)
			(stroke
				(width 0.1)
				(type default)
			)
			(layer "F.Fab")
		)
		(fp_line
			(start -1.649984 -0.899922)
			(end -1.649984 0.899922)
			(stroke
				(width 0.1)
				(type default)
			)
			(layer "F.Fab")
		)
		(pad "1A" smd rect
			(at -1.700022 0 180)
			(size 1.4986 2.0066)
			(layers "F.Cu" "F.Mask" "F.Paste")
			(net "P0V8_PEX1")
		)
		(pad "1B" smd rect
			(at -1.077722 0 180)
			(size 0.254 0.508)
			(layers "F.Cu" "F.Mask" "F.Paste")
			(net "P0V8_PEX1")
		)
		(pad "2A" smd rect
			(at 1.700022 0 180)
			(size 1.4986 2.0066)
			(layers "F.Cu" "F.Mask" "F.Paste")
			(net "P0V8_SERDES_VDDA_PEX1")
		)
		(pad "2B" smd rect
			(at 1.077722 0 180)
			(size 0.254 0.508)
			(layers "F.Cu" "F.Mask" "F.Paste")
			(net "P0V8_SERDES_VDDA_PEX1")
		)
	)
	(footprint ""
		(layer "F.Cu")
		(at 312.21934 -154.304746 180)
		(property "Reference" "C425"
			(at 0 0 180)
			(layer "F.SilkS")
			(hide yes)
			(effects
				(font
					(size 1.27 1.27)
				)
			)
		)
		(property "Value" ""
			(at 0 0 180)
			(layer "F.Fab")
			(effects
				(font
					(size 1.27 1.27)
				)
			)
		)
		(duplicate_pad_numbers_are_jumpers no)
		(fp_line
			(start 0.299974 0.150114)
			(end -0.299974 0.150114)
			(stroke
				(width 0.1)
				(type default)
			)
			(layer "F.Fab")
		)
		(fp_line
			(start 0.299974 -0.150114)
			(end 0.299974 0.150114)
			(stroke
				(width 0.1)
				(type default)
			)
			(layer "F.Fab")
		)
		(fp_line
			(start -0.299974 0.150114)
			(end -0.299974 -0.150114)
			(stroke
				(width 0.1)
				(type default)
			)
			(layer "F.Fab")
		)
		(fp_line
			(start -0.299974 -0.150114)
			(end 0.299974 -0.150114)
			(stroke
				(width 0.1)
				(type default)
			)
			(layer "F.Fab")
		)
		(pad "1" smd rect
			(at -0.2667 0 180)
			(size 0.3048 0.381)
			(layers "F.Cu" "F.Mask" "F.Paste")
			(net "P5E_PEX2_STN0_TX_DN<14>")
		)
		(pad "2" smd rect
			(at 0.2667 0 180)
			(size 0.3048 0.381)
			(layers "F.Cu" "F.Mask" "F.Paste")
			(net "P5E_PEX2_STN0_TX_C_DN<14>")
		)
	)
)
